(kicad_pcb
	(version 20241229)
	(generator "pcbnew")
	(generator_version "9.0")
	(general
		(thickness 1.294)
		(legacy_teardrops no)
	)
	(paper "A3")
	(title_block
		(title "Kintex 410T devboard")
		(date "2024-04-03")
		(rev "1.1.2")
		(comment 9 "footprints 777-782 of 975")
	)
	(layers
		(0 "F.Cu" mixed)
		(4 "In1.Cu" power)
		(6 "In2.Cu" power)
		(8 "In3.Cu" mixed)
		(10 "In4.Cu" power)
		(12 "In5.Cu" mixed)
		(14 "In6.Cu" power)
		(16 "In7.Cu" mixed)
		(18 "In8.Cu" power)
		(2 "B.Cu" mixed)
		(9 "F.Adhes" user "F.Adhesive")
		(11 "B.Adhes" user "B.Adhesive")
		(13 "F.Paste" user)
		(15 "B.Paste" user)
		(5 "F.SilkS" user "F.Silkscreen")
		(7 "B.SilkS" user "B.Silkscreen")
		(1 "F.Mask" user)
		(3 "B.Mask" user)
		(17 "Dwgs.User" user "User.Drawings")
		(19 "Cmts.User" user "User.Comments")
		(21 "Eco1.User" user "User.Eco1")
		(23 "Eco2.User" user "User.Eco2")
		(25 "Edge.Cuts" user)
		(27 "Margin" user)
		(31 "F.CrtYd" user "F.Courtyard")
		(29 "B.CrtYd" user "B.Courtyard")
		(35 "F.Fab" user)
		(33 "B.Fab" user)
	)
	(footprint "antmicro-footprints:R_0402_1005Metric"
		(layer "B.Cu")
		(at 244.099999 84.699999 90)
		(descr "Resistor SMD 0402")
		(tags "resistor SMD 0402")
		(property "Reference" "R127"
			(at -0.725001 0.450001 270)
			(layer "B.SilkS")
			(effects
				(font
					(size 0.7 0.7)
					(thickness 0.15)
				)
				(justify left bottom mirror)
			)
		)
		(property "Value" "R_100R_0402"
			(at 0 -1.4 270)
			(layer "B.Fab")
			(effects
				(font
					(size 0.7 0.7)
					(thickness 0.15)
				)
				(justify left bottom mirror)
			)
		)
		(property "Description" "SMD Chip Resistor, 100 ohm, ± 1%, 62.5 mW, 0402 [1005 Metric], Thick Film, General Purpose"
			(at 0 0 90)
			(layer "F.Fab")
			(hide yes)
			(effects
				(font
					(size 1.27 1.27)
					(thickness 0.15)
				)
			)
		)
		(property "Author" "Antmicro"
			(at 328.799998 -159.4 0)
			(layer "B.Fab")
			(hide yes)
			(effects
				(font
					(size 1 1)
					(thickness 0.15)
				)
				(justify mirror)
			)
		)
		(property "License" "Apache-2.0"
			(at 328.799998 -159.4 0)
			(layer "B.Fab")
			(hide yes)
			(effects
				(font
					(size 1 1)
					(thickness 0.15)
				)
				(justify mirror)
			)
		)
		(property "MPN" "CR0402-FX-1000GLF"
			(at 328.799998 -159.4 0)
			(layer "B.Fab")
			(hide yes)
			(effects
				(font
					(size 1 1)
					(thickness 0.15)
				)
				(justify mirror)
			)
		)
		(property "Manufacturer" "Bourns"
			(at 328.799998 -159.4 0)
			(layer "B.Fab")
			(hide yes)
			(effects
				(font
					(size 1 1)
					(thickness 0.15)
				)
				(justify mirror)
			)
		)
		(property "Tolerance" "1%"
			(at 328.799998 -159.4 0)
			(layer "B.Fab")
			(hide yes)
			(effects
				(font
					(size 1 1)
					(thickness 0.15)
				)
				(justify mirror)
			)
		)
		(property "Val" "100R"
			(at 328.799998 -159.4 0)
			(layer "B.Fab")
			(hide yes)
			(effects
				(font
					(size 1 1)
					(thickness 0.15)
				)
				(justify mirror)
			)
		)
		(sheetname "User GPIO + LED + button + DIP switch")
		(sheetfile "user-gpio.kicad_sch")
		(attr smd)
		(fp_rect
			(start -0.925 0.47)
			(end 0.925 -0.47)
			(stroke
				(width 0.05)
				(type default)
			)
			(fill no)
			(layer "B.CrtYd")
		)
		(fp_rect
			(start -0.5 0.25)
			(end 0.5 -0.25)
			(stroke
				(width 0.15)
				(type solid)
			)
			(fill no)
			(layer "B.Fab")
		)
		(pad "1" smd roundrect
			(at -0.48 0 90)
			(size 0.59 0.64)
			(layers "B.Cu" "B.Mask" "B.Paste")
			(roundrect_rratio 0.25)
			(net 472 "/FPGA Bank 12 & 13/PMOD_B.IO4")
			(pintype "passive")
		)
		(pad "2" smd roundrect
			(at 0.48 0 90)
			(size 0.59 0.64)
			(layers "B.Cu" "B.Mask" "B.Paste")
			(roundrect_rratio 0.25)
			(net 811 "/User GPIO + LED + button + DIP switch/PMOD_B_4")
			(pintype "passive")
		)
	)
	(footprint "antmicro-footprints:C_0402_1005Metric"
		(layer "B.Cu")
		(at 158.6 144.5 -90)
		(descr "Capacitor SMD 0402")
		(tags "capacitor SMD 0402")
		(property "Reference" "C173"
			(at -1.9 3.475 90)
			(layer "B.SilkS")
			(effects
				(font
					(size 0.7 0.7)
					(thickness 0.15)
				)
				(justify left bottom mirror)
			)
		)
		(property "Value" "C_100n_0402"
			(at 0 -1.169 90)
			(layer "B.Fab")
			(effects
				(font
					(size 0.7 0.7)
					(thickness 0.15)
				)
				(justify left bottom mirror)
			)
		)
		(property "Description" "SMD Multilayer Ceramic Capacitor, 0.1 µF, 50 V, 0402 [1005 Metric], ± 10%, X5R, GRM Series"
			(at 0 0 270)
			(layer "F.Fab")
			(hide yes)
			(effects
				(font
					(size 1.27 1.27)
					(thickness 0.15)
				)
			)
		)
		(property "Author" "Antmicro"
			(at 14.1 303.1 0)
			(layer "B.Fab")
			(hide yes)
			(effects
				(font
					(size 1 1)
					(thickness 0.15)
				)
				(justify mirror)
			)
		)
		(property "Dielectric" "X5R"
			(at 14.1 303.1 0)
			(layer "B.Fab")
			(hide yes)
			(effects
				(font
					(size 1 1)
					(thickness 0.15)
				)
				(justify mirror)
			)
		)
		(property "License" "Apache-2.0"
			(at 14.1 303.1 0)
			(layer "B.Fab")
			(hide yes)
			(effects
				(font
					(size 1 1)
					(thickness 0.15)
				)
				(justify mirror)
			)
		)
		(property "MPN" "GRM155R61H104KE14D"
			(at 14.1 303.1 0)
			(layer "B.Fab")
			(hide yes)
			(effects
				(font
					(size 1 1)
					(thickness 0.15)
				)
				(justify mirror)
			)
		)
		(property "Manufacturer" "Murata"
			(at 14.1 303.1 0)
			(layer "B.Fab")
			(hide yes)
			(effects
				(font
					(size 1 1)
					(thickness 0.15)
				)
				(justify mirror)
			)
		)
		(property "Val" "100n"
			(at 14.1 303.1 0)
			(layer "B.Fab")
			(hide yes)
			(effects
				(font
					(size 1 1)
					(thickness 0.15)
				)
				(justify mirror)
			)
		)
		(property "Voltage" "50V"
			(at 14.1 303.1 0)
			(layer "B.Fab")
			(hide yes)
			(effects
				(font
					(size 1 1)
					(thickness 0.15)
				)
				(justify mirror)
			)
		)
		(sheetname "DRAM + SRAM")
		(sheetfile "ram.kicad_sch")
		(attr smd)
		(fp_rect
			(start -0.925 0.47)
			(end 0.925 -0.47)
			(stroke
				(width 0.05)
				(type default)
			)
			(fill no)
			(layer "B.CrtYd")
		)
		(fp_line
			(start -0.494 0.25)
			(end 0.504 0.25)
			(stroke
				(width 0.15)
				(type solid)
			)
			(layer "B.Fab")
		)
		(fp_line
			(start 0.504 0.25)
			(end 0.504 -0.248)
			(stroke
				(width 0.15)
				(type solid)
			)
			(layer "B.Fab")
		)
		(fp_line
			(start -0.494 -0.248)
			(end -0.494 0.25)
			(stroke
				(width 0.15)
				(type solid)
			)
			(layer "B.Fab")
		)
		(fp_line
			(start 0.504 -0.248)
			(end -0.494 -0.248)
			(stroke
				(width 0.15)
				(type solid)
			)
			(layer "B.Fab")
		)
		(pad "1" smd roundrect
			(at -0.48 0 270)
			(size 0.59 0.64)
			(layers "B.Cu" "B.Mask" "B.Paste")
			(roundrect_rratio 0.25)
			(net 1 "GND")
			(pintype "passive")
		)
		(pad "2" smd roundrect
			(at 0.48 0 270)
			(size 0.59 0.64)
			(layers "B.Cu" "B.Mask" "B.Paste")
			(roundrect_rratio 0.25)
			(net 7 "+0V675_VTT")
			(pintype "passive")
		)
	)
	(footprint "antmicro-footprints:R_0402_1005Metric"
		(layer "B.Cu")
		(at 214.199999 77.899999 -90)
		(descr "Resistor SMD 0402")
		(tags "resistor SMD 0402")
		(property "Reference" "R120"
			(at -3.599999 -0.375001 90)
			(layer "B.SilkS")
			(effects
				(font
					(size 0.7 0.7)
					(thickness 0.15)
				)
				(justify left bottom mirror)
			)
		)
		(property "Value" "R_100R_0402"
			(at 0 -1.4 90)
			(layer "B.Fab")
			(effects
				(font
					(size 0.7 0.7)
					(thickness 0.15)
				)
				(justify left bottom mirror)
			)
		)
		(property "Description" "SMD Chip Resistor, 100 ohm, ± 1%, 62.5 mW, 0402 [1005 Metric], Thick Film, General Purpose"
			(at 0 0 270)
			(layer "F.Fab")
			(hide yes)
			(effects
				(font
					(size 1.27 1.27)
					(thickness 0.15)
				)
			)
		)
		(property "Author" "Antmicro"
			(at 136.3 292.099998 0)
			(layer "B.Fab")
			(hide yes)
			(effects
				(font
					(size 1 1)
					(thickness 0.15)
				)
				(justify mirror)
			)
		)
		(property "License" "Apache-2.0"
			(at 136.3 292.099998 0)
			(layer "B.Fab")
			(hide yes)
			(effects
				(font
					(size 1 1)
					(thickness 0.15)
				)
				(justify mirror)
			)
		)
		(property "MPN" "CR0402-FX-1000GLF"
			(at 136.3 292.099998 0)
			(layer "B.Fab")
			(hide yes)
			(effects
				(font
					(size 1 1)
					(thickness 0.15)
				)
				(justify mirror)
			)
		)
		(property "Manufacturer" "Bourns"
			(at 136.3 292.099998 0)
			(layer "B.Fab")
			(hide yes)
			(effects
				(font
					(size 1 1)
					(thickness 0.15)
				)
				(justify mirror)
			)
		)
		(property "Tolerance" "1%"
			(at 136.3 292.099998 0)
			(layer "B.Fab")
			(hide yes)
			(effects
				(font
					(size 1 1)
					(thickness 0.15)
				)
				(justify mirror)
			)
		)
		(property "Val" "100R"
			(at 136.3 292.099998 0)
			(layer "B.Fab")
			(hide yes)
			(effects
				(font
					(size 1 1)
					(thickness 0.15)
				)
				(justify mirror)
			)
		)
		(sheetname "User GPIO + LED + button + DIP switch")
		(sheetfile "user-gpio.kicad_sch")
		(attr smd)
		(fp_rect
			(start -0.925 0.47)
			(end 0.925 -0.47)
			(stroke
				(width 0.05)
				(type default)
			)
			(fill no)
			(layer "B.CrtYd")
		)
		(fp_rect
			(start -0.5 0.25)
			(end 0.5 -0.25)
			(stroke
				(width 0.15)
				(type solid)
			)
			(fill no)
			(layer "B.Fab")
		)
		(pad "1" smd roundrect
			(at -0.48 0 270)
			(size 0.59 0.64)
			(layers "B.Cu" "B.Mask" "B.Paste")
			(roundrect_rratio 0.25)
			(net 456 "/FPGA Bank 12 & 13/PMOD_A.IO1")
			(pintype "passive")
		)
		(pad "2" smd roundrect
			(at 0.48 0 270)
			(size 0.59 0.64)
			(layers "B.Cu" "B.Mask" "B.Paste")
			(roundrect_rratio 0.25)
			(net 809 "/User GPIO + LED + button + DIP switch/PMOD_A_1")
			(pintype "passive")
		)
	)
	(footprint "antmicro-footprints:C_0402_1005Metric"
		(layer "B.Cu")
		(at 196 137.5)
		(descr "Capacitor SMD 0402")
		(tags "capacitor SMD 0402")
		(property "Reference" "C78"
			(at 1.275 1.225 180)
			(layer "B.SilkS")
			(effects
				(font
					(size 0.7 0.7)
					(thickness 0.15)
				)
				(justify left bottom mirror)
			)
		)
		(property "Value" "C_100n_0402"
			(at 0 -1.169 180)
			(layer "B.Fab")
			(effects
				(font
					(size 0.7 0.7)
					(thickness 0.15)
				)
				(justify left bottom mirror)
			)
		)
		(property "Description" "SMD Multilayer Ceramic Capacitor, 0.1 µF, 50 V, 0402 [1005 Metric], ± 10%, X5R, GRM Series"
			(at 0 0 0)
			(layer "F.Fab")
			(hide yes)
			(effects
				(font
					(size 1.27 1.27)
					(thickness 0.15)
				)
			)
		)
		(property "Author" "Antmicro"
			(at 0 0 0)
			(layer "B.Fab")
			(hide yes)
			(effects
				(font
					(size 1 1)
					(thickness 0.15)
				)
				(justify mirror)
			)
		)
		(property "Dielectric" "X5R"
			(at 0 0 0)
			(layer "B.Fab")
			(hide yes)
			(effects
				(font
					(size 1 1)
					(thickness 0.15)
				)
				(justify mirror)
			)
		)
		(property "License" "Apache-2.0"
			(at 0 0 0)
			(layer "B.Fab")
			(hide yes)
			(effects
				(font
					(size 1 1)
					(thickness 0.15)
				)
				(justify mirror)
			)
		)
		(property "MPN" "GRM155R61H104KE14D"
			(at 0 0 0)
			(layer "B.Fab")
			(hide yes)
			(effects
				(font
					(size 1 1)
					(thickness 0.15)
				)
				(justify mirror)
			)
		)
		(property "Manufacturer" "Murata"
			(at 0 0 0)
			(layer "B.Fab")
			(hide yes)
			(effects
				(font
					(size 1 1)
					(thickness 0.15)
				)
				(justify mirror)
			)
		)
		(property "Val" "100n"
			(at 0 0 0)
			(layer "B.Fab")
			(hide yes)
			(effects
				(font
					(size 1 1)
					(thickness 0.15)
				)
				(justify mirror)
			)
		)
		(property "Voltage" "50V"
			(at 0 0 0)
			(layer "B.Fab")
			(hide yes)
			(effects
				(font
					(size 1 1)
					(thickness 0.15)
				)
				(justify mirror)
			)
		)
		(sheetname "FPGA Bank 33 & 34")
		(sheetfile "fpga-bank-33-34.kicad_sch")
		(attr smd)
		(fp_rect
			(start -0.925 0.47)
			(end 0.925 -0.47)
			(stroke
				(width 0.05)
				(type default)
			)
			(fill no)
			(layer "B.CrtYd")
		)
		(fp_line
			(start -0.494 -0.248)
			(end -0.494 0.25)
			(stroke
				(width 0.15)
				(type solid)
			)
			(layer "B.Fab")
		)
		(fp_line
			(start -0.494 0.25)
			(end 0.504 0.25)
			(stroke
				(width 0.15)
				(type solid)
			)
			(layer "B.Fab")
		)
		(fp_line
			(start 0.504 -0.248)
			(end -0.494 -0.248)
			(stroke
				(width 0.15)
				(type solid)
			)
			(layer "B.Fab")
		)
		(fp_line
			(start 0.504 0.25)
			(end 0.504 -0.248)
			(stroke
				(width 0.15)
				(type solid)
			)
			(layer "B.Fab")
		)
		(pad "1" smd roundrect
			(at -0.48 0)
			(size 0.59 0.64)
			(layers "B.Cu" "B.Mask" "B.Paste")
			(roundrect_rratio 0.25)
			(net 1 "GND")
			(pintype "passive")
		)
		(pad "2" smd roundrect
			(at 0.48 0)
			(size 0.59 0.64)
			(layers "B.Cu" "B.Mask" "B.Paste")
			(roundrect_rratio 0.25)
			(net 26 "+1V8")
			(pintype "passive")
		)
	)
	(footprint "antmicro-footprints:C_0603_1608Metric"
		(layer "B.Cu")
		(at 200 141.8 90)
		(descr "Capacitor SMD 0603")
		(tags "capacitor 0603")
		(property "Reference" "C380"
			(at -1.375 -0.525 90)
			(layer "B.SilkS")
			(effects
				(font
					(size 0.7 0.7)
					(thickness 0.15)
				)
				(justify right bottom mirror)
			)
		)
		(property "Value" "C_47u_0603"
			(at 0 -1.6 90)
			(layer "B.Fab")
			(effects
				(font
					(size 0.7 0.7)
					(thickness 0.15)
				)
				(justify right bottom mirror)
			)
		)
		(property "Description" "SMD Multilayer Ceramic Capacitor, 47 µF, 6.3 V, 0603 [1608 Metric], ± 20%, X5R, GRM Series"
			(at 0 0 90)
			(layer "F.Fab")
			(hide yes)
			(effects
				(font
					(size 1.27 1.27)
					(thickness 0.15)
				)
			)
		)
		(property "Author" "Antmicro"
			(at 341.8 -58.2 0)
			(layer "B.Fab")
			(hide yes)
			(effects
				(font
					(size 1 1)
					(thickness 0.15)
				)
				(justify mirror)
			)
		)
		(property "Dielectric" ""
			(at 341.8 -58.2 0)
			(layer "B.Fab")
			(hide yes)
			(effects
				(font
					(size 1 1)
					(thickness 0.15)
				)
				(justify mirror)
			)
		)
		(property "License" "Apache-2.0"
			(at 341.8 -58.2 0)
			(layer "B.Fab")
			(hide yes)
			(effects
				(font
					(size 1 1)
					(thickness 0.15)
				)
				(justify mirror)
			)
		)
		(property "MPN" "GRM188R60J476ME15D"
			(at 341.8 -58.2 0)
			(layer "B.Fab")
			(hide yes)
			(effects
				(font
					(size 1 1)
					(thickness 0.15)
				)
				(justify mirror)
			)
		)
		(property "Manufacturer" "Murata"
			(at 341.8 -58.2 0)
			(layer "B.Fab")
			(hide yes)
			(effects
				(font
					(size 1 1)
					(thickness 0.15)
				)
				(justify mirror)
			)
		)
		(property "Val" "47u"
			(at 341.8 -58.2 0)
			(layer "B.Fab")
			(hide yes)
			(effects
				(font
					(size 1 1)
					(thickness 0.15)
				)
				(justify mirror)
			)
		)
		(property "Voltage" ""
			(at 341.8 -58.2 0)
			(layer "B.Fab")
			(hide yes)
			(effects
				(font
					(size 1 1)
					(thickness 0.15)
				)
				(justify mirror)
			)
		)
		(sheetname "FPGA supply")
		(sheetfile "fpga-supply.kicad_sch")
		(attr smd)
		(fp_line
			(start -0.15 -0.4)
			(end 0.15 -0.4)
			(stroke
				(width 0.15)
				(type solid)
			)
			(layer "B.SilkS")
		)
		(fp_line
			(start -0.15 0.4)
			(end 0.15 0.4)
			(stroke
				(width 0.15)
				(type solid)
			)
			(layer "B.SilkS")
		)
		(fp_rect
			(start -1.25 0.65)
			(end 1.25 -0.65)
			(stroke
				(width 0.05)
				(type solid)
			)
			(fill no)
			(layer "B.CrtYd")
		)
		(fp_rect
			(start -0.8 0.4)
			(end 0.8 -0.4)
			(stroke
				(width 0.15)
				(type solid)
			)
			(fill no)
			(layer "B.Fab")
		)
		(pad "1" smd roundrect
			(at -0.7 0 90)
			(size 0.8 1)
			(layers "B.Cu" "B.Mask" "B.Paste")
			(roundrect_rratio 0.2)
			(net 1 "GND")
			(pintype "passive")
		)
		(pad "2" smd roundrect
			(at 0.7 0 90)
			(size 0.8 1)
			(layers "B.Cu" "B.Mask" "B.Paste")
			(roundrect_rratio 0.2)
			(net 650 "+1V0")
			(pintype "passive")
		)
	)
	(footprint "antmicro-footprints:C_0402_1005Metric"
		(layer "B.Cu")
		(at 213 128.52 180)
		(descr "Capacitor SMD 0402")
		(tags "capacitor SMD 0402")
		(property "Reference" "C13"
			(at -1.075 0.45 0)
			(layer "B.SilkS")
			(effects
				(font
					(size 0.7 0.7)
					(thickness 0.15)
				)
				(justify left bottom mirror)
			)
		)
		(property "Value" "C_100n_0402"
			(at 0 -1.169 0)
			(layer "B.Fab")
			(effects
				(font
					(size 0.7 0.7)
					(thickness 0.15)
				)
				(justify left bottom mirror)
			)
		)
		(property "Description" "SMD Multilayer Ceramic Capacitor, 0.1 µF, 50 V, 0402 [1005 Metric], ± 10%, X5R, GRM Series"
			(at 0 0 180)
			(layer "F.Fab")
			(hide yes)
			(effects
				(font
					(size 1.27 1.27)
					(thickness 0.15)
				)
			)
		)
		(property "Author" "Antmicro"
			(at 426 257.04 0)
			(layer "B.Fab")
			(hide yes)
			(effects
				(font
					(size 1 1)
					(thickness 0.15)
				)
				(justify mirror)
			)
		)
		(property "Dielectric" "X5R"
			(at 426 257.04 0)
			(layer "B.Fab")
			(hide yes)
			(effects
				(font
					(size 1 1)
					(thickness 0.15)
				)
				(justify mirror)
			)
		)
		(property "License" "Apache-2.0"
			(at 426 257.04 0)
			(layer "B.Fab")
			(hide yes)
			(effects
				(font
					(size 1 1)
					(thickness 0.15)
				)
				(justify mirror)
			)
		)
		(property "MPN" "GRM155R61H104KE14D"
			(at 426 257.04 0)
			(layer "B.Fab")
			(hide yes)
			(effects
				(font
					(size 1 1)
					(thickness 0.15)
				)
				(justify mirror)
			)
		)
		(property "Manufacturer" "Murata"
			(at 426 257.04 0)
			(layer "B.Fab")
			(hide yes)
			(effects
				(font
					(size 1 1)
					(thickness 0.15)
				)
				(justify mirror)
			)
		)
		(property "Val" "100n"
			(at 426 257.04 0)
			(layer "B.Fab")
			(hide yes)
			(effects
				(font
					(size 1 1)
					(thickness 0.15)
				)
				(justify mirror)
			)
		)
		(property "Voltage" "50V"
			(at 426 257.04 0)
			(layer "B.Fab")
			(hide yes)
			(effects
				(font
					(size 1 1)
					(thickness 0.15)
				)
				(justify mirror)
			)
		)
		(sheetname "FPGA Bank 14 & 15")
		(sheetfile "fpga-bank-14-15.kicad_sch")
		(attr smd)
		(fp_rect
			(start -0.925 0.47)
			(end 0.925 -0.47)
			(stroke
				(width 0.05)
				(type default)
			)
			(fill no)
			(layer "B.CrtYd")
		)
		(fp_line
			(start 0.504 0.25)
			(end 0.504 -0.248)
			(stroke
				(width 0.15)
				(type solid)
			)
			(layer "B.Fab")
		)
		(fp_line
			(start 0.504 -0.248)
			(end -0.494 -0.248)
			(stroke
				(width 0.15)
				(type solid)
			)
			(layer "B.Fab")
		)
		(fp_line
			(start -0.494 0.25)
			(end 0.504 0.25)
			(stroke
				(width 0.15)
				(type solid)
			)
			(layer "B.Fab")
		)
		(fp_line
			(start -0.494 -0.248)
			(end -0.494 0.25)
			(stroke
				(width 0.15)
				(type solid)
			)
			(layer "B.Fab")
		)
		(pad "1" smd roundrect
			(at -0.48 0 180)
			(size 0.59 0.64)
			(layers "B.Cu" "B.Mask" "B.Paste")
			(roundrect_rratio 0.25)
			(net 1 "GND")
			(pintype "passive")
		)
		(pad "2" smd roundrect
			(at 0.48 0 180)
			(size 0.59 0.64)
			(layers "B.Cu" "B.Mask" "B.Paste")
			(roundrect_rratio 0.25)
			(net 24 "+3V3")
			(pintype "passive")
		)
	)
)
